FILE_TYPE = CONNECTIVITY;
{Allegro Design Entry HDL 16.6-p007 (v16-6-112F) 10/10/2012}
"PAGE_NUMBER" = 47;
0"NC";
1"M_C_DQS_DN<17:0>";
2"M_C_DQS_DP<17:0>";
3"M_C_DQ<63:0>";
4"M_C_MA<17:0>";
5"M_C_CLK_DN<3:0>";
6"M_C_CLK_DP<3:0>";
7"M_C_BA<1:0>";
8"M_C_CS_N<7:0>";
9"M_C_ECC<7:0>";
10"M_C_CKE<3:0>";
11"M_C_BG<1:0>";
12"M_C_ODT<3:0>";
13"PVTT_ABC\g";
14"PVDDQ_ABC\g";
15"GND\g";
16"GND\g";
17"GND\g";
18"PVPP_ABC\g";
19"PVPP_ABC\g";
20"P12V_NVDIMM_ABC\g";
21"GND\g";
22"M_C_DQ<56>";
23"M_C_MA<13>";
24"M_C_MA<7>";
25"M_C_MA<6>";
26"M_C_DQS_DN<13>";
27"M_C_VREF";
28"TP_CH_C_DIMM_C0_RFU_1";
29"TP_CH_C_DIMM_C0_RFU_0";
30"TP_CH_C_DIMM_C0_RFU_2";
31"M_C_ALERT_N";
32"M_C_ACT_N";
33"SMB_DDR_ABC_VPP_SCL";
34"SMB_DDR_ABC_VPP_SDA";
35"FM_ADR_COMPLETE_ABC_N";
36"FM_DIMM_EVENT_COD_N";
37"M_ABC_RST_N";
38"M_C_PAR";
39"M_C_C<2>";
40"M_C_CS_N<0>";
41"M_C_CKE<0>";
42"M_C_ODT<1>";
43"M_C_ODT<0>";
44"M_C_ECC<6>";
45"M_C_MA<2>";
46"M_C_BA<0>";
47"M_C_BG<1>";
48"M_C_BG<0>";
49"M_C_CKE<1>";
50"M_C_ECC<1>";
51"M_C_ECC<0>";
52"M_C_ECC<3>";
53"M_C_ECC<2>";
54"M_C_ECC<5>";
55"M_C_ECC<4>";
56"M_C_ECC<7>";
57"M_C_MA<5>";
58"M_C_MA<4>";
59"M_C_MA<3>";
60"M_C_MA<1>";
61"M_C_MA<0>";
62"M_C_CS_N<1>";
63"M_C_CS_N<2>";
64"M_C_CS_N<3>";
65"M_C_BA<1>";
66"M_C_CLK_DP<1>";
67"M_C_CLK_DN<0>";
68"M_C_CLK_DP<0>";
69"M_C_CLK_DN<1>";
70"M_C_DQ<1>";
71"M_C_DQ<4>";
72"M_C_DQ<5>";
73"M_C_DQ<2>";
74"M_C_DQ<3>";
75"M_C_DQ<0>";
76"M_C_DQ<7>";
77"M_C_DQ<6>";
78"M_C_DQ<9>";
79"M_C_DQ<8>";
80"M_C_DQ<11>";
81"M_C_DQ<16>";
82"M_C_DQ<14>";
83"M_C_DQ<10>";
84"M_C_DQ<13>";
85"M_C_DQ<12>";
86"M_C_DQ<15>";
87"M_C_DQ<17>";
88"M_C_DQ<19>";
89"M_C_DQ<18>";
90"M_C_DQ<21>";
91"M_C_DQ<20>";
92"M_C_DQ<27>";
93"M_C_DQ<26>";
94"M_C_DQ<23>";
95"M_C_DQ<22>";
96"M_C_DQ<25>";
97"M_C_DQ<24>";
98"M_C_DQ<31>";
99"M_C_DQ<30>";
100"M_C_DQ<29>";
101"M_C_DQ<28>";
102"M_C_DQ<39>";
103"M_C_DQ<37>";
104"M_C_DQ<34>";
105"M_C_DQ<33>";
106"M_C_DQ<32>";
107"M_C_DQ<35>";
108"M_C_DQ<36>";
109"M_C_DQ<38>";
110"M_C_DQ<41>";
111"M_C_DQ<40>";
112"M_C_DQ<46>";
113"M_C_DQ<49>";
114"M_C_DQ<48>";
115"M_C_DQ<51>";
116"M_C_DQ<50>";
117"M_C_DQ<43>";
118"M_C_DQ<42>";
119"M_C_DQ<45>";
120"M_C_DQ<44>";
121"M_C_DQ<47>";
122"M_C_MA<16>";
123"M_C_MA<15>";
124"M_C_MA<14>";
125"M_C_MA<11>";
126"M_C_MA<10>";
127"M_C_MA<9>";
128"M_C_MA<8>";
129"M_C_MA<17>";
130"M_C_MA<12>";
131"M_C_DQ<63>";
132"M_C_DQ<60>";
133"M_C_DQ<53>";
134"M_C_DQ<52>";
135"M_C_DQ<55>";
136"M_C_DQ<59>";
137"M_C_DQ<54>";
138"M_C_DQ<57>";
139"M_C_DQ<58>";
140"M_C_DQ<61>";
141"M_C_DQ<62>";
142"M_C_DQS_DN<6>";
143"M_C_DQS_DP<5>";
144"M_C_DQS_DN<5>";
145"M_C_DQS_DP<4>";
146"M_C_DQS_DN<4>";
147"M_C_DQS_DP<3>";
148"M_C_DQS_DN<3>";
149"M_C_DQS_DP<2>";
150"M_C_DQS_DN<2>";
151"M_C_DQS_DP<1>";
152"M_C_DQS_DN<1>";
153"M_C_DQS_DP<0>";
154"M_C_DQS_DN<0>";
155"M_C_DQS_DP<9>";
156"M_C_DQS_DN<9>";
157"M_C_DQS_DP<8>";
158"M_C_DQS_DN<8>";
159"M_C_DQS_DP<7>";
160"M_C_DQS_DN<7>";
161"M_C_DQS_DP<6>";
162"M_C_DQS_DP<16>";
163"M_C_DQS_DN<16>";
164"M_C_DQS_DP<15>";
165"M_C_DQS_DN<15>";
166"M_C_DQS_DP<14>";
167"M_C_DQS_DN<14>";
168"M_C_DQS_DP<13>";
169"M_C_DQS_DP<12>";
170"M_C_DQS_DN<12>";
171"M_C_DQS_DP<11>";
172"M_C_DQS_DN<11>";
173"M_C_DQS_DP<10>";
174"M_C_DQS_DN<10>";
175"M_C_DQS_DP<17>";
176"M_C_DQS_DN<17>";
%"TAP"
"6","(700,4900)","2","mstr_standard","I10";
;
CDS_LIB"mstr_standard"
BODY_TYPE"PLUMBING"
HDL_TAP"TRUE";
"B \NAC \NWC"2;
"S \NAC"
BN"14"166;
%"TAP"
"6","(-1700,1900)","2","mstr_standard","I100";
;
CDS_LIB"mstr_standard"
BODY_TYPE"PLUMBING"
HDL_TAP"TRUE";
"B \NAC \NWC"3;
"S \NAC"
BN"9"78;
%"TAP"
"6","(-1700,2000)","2","mstr_standard","I101";
;
CDS_LIB"mstr_standard"
BODY_TYPE"PLUMBING"
HDL_TAP"TRUE";
"B \NAC \NWC"3;
"S \NAC"
BN"11"80;
%"TAP"
"6","(-1700,1950)","2","mstr_standard","I102";
;
CDS_LIB"mstr_standard"
BODY_TYPE"PLUMBING"
HDL_TAP"TRUE";
"B \NAC \NWC"3;
"S \NAC"
BN"8"79;
%"TAP"
"6","(-1700,1750)","2","mstr_standard","I103";
;
CDS_LIB"mstr_standard"
BODY_TYPE"PLUMBING"
HDL_TAP"TRUE";
"B \NAC \NWC"3;
"S \NAC"
BN"4"71;
%"TAP"
"6","(-1700,1800)","2","mstr_standard","I104";
;
CDS_LIB"mstr_standard"
BODY_TYPE"PLUMBING"
HDL_TAP"TRUE";
"B \NAC \NWC"3;
"S \NAC"
BN"7"76;
%"TAP"
"6","(-1700,1850)","2","mstr_standard","I105";
;
CDS_LIB"mstr_standard"
BODY_TYPE"PLUMBING"
HDL_TAP"TRUE";
"B \NAC \NWC"3;
"S \NAC"
BN"6"77;
%"TAP"
"6","(-1700,1700)","2","mstr_standard","I106";
;
CDS_LIB"mstr_standard"
BODY_TYPE"PLUMBING"
HDL_TAP"TRUE";
"B \NAC \NWC"3;
"S \NAC"
BN"5"72;
%"TAP"
"6","(-1700,1650)","2","mstr_standard","I107";
;
CDS_LIB"mstr_standard"
BODY_TYPE"PLUMBING"
HDL_TAP"TRUE";
"B \NAC \NWC"3;
"S \NAC"
BN"2"73;
%"TAP"
"6","(-1700,1550)","2","mstr_standard","I108";
;
CDS_LIB"mstr_standard"
BODY_TYPE"PLUMBING"
HDL_TAP"TRUE";
"B \NAC \NWC"3;
"S \NAC"
BN"0"75;
%"TAP"
"6","(-1700,1600)","2","mstr_standard","I109";
;
CDS_LIB"mstr_standard"
BODY_TYPE"PLUMBING"
HDL_TAP"TRUE";
"B \NAC \NWC"3;
"S \NAC"
BN"3"74;
%"TAP"
"6","(-1700,1500)","2","mstr_standard","I110";
;
CDS_LIB"mstr_standard"
BODY_TYPE"PLUMBING"
HDL_TAP"TRUE";
"B \NAC \NWC"3;
"S \NAC"
BN"1"70;
%"SCONN288_H44441004"
"1","(-2450,3000)","0","mstr_sconn","I111";
;
CDS_SEC"1"
PART_NUMBER"H44441-004"
MATERIAL"SCONN"
LOCATION"J4G3"
PACK_TYPE"PIP"
BOM_COST"MEM"
CDS_LIB"mstr_sconn"
SEC_TYPE"PIP"
SEC"1"
CDS_LOCATION"J4G3"
ROOM"DDR4_CH_C";
"DQ<63>"
$PN"280"141;
"DQ<62>"
$PN"135"131;
"DQ<61>"
$PN"273"132;
"DQ<5>"
$PN"148"71;
"DQ<4>"
$PN"3"72;
"DQ<3>"
$PN"157"73;
"DQ<2>"
$PN"12"74;
"DQ<47>"
$PN"258"112;
"DQ<48>"
$PN"119"113;
"DQ<49>"
$PN"264"114;
"DQ<50>"
$PN"126"115;
"DQ<51>"
$PN"271"116;
"DQ<52>"
$PN"117"133;
"DQ<53>"
$PN"262"134;
"DQ<54>"
$PN"124"135;
"DQ<58>"
$PN"137"136;
"DQ<57>"
$PN"275"22;
"SAVE_N_NC"
$PN"230"35;
"RFU<1>"
$PN"227"28;
"RFU<0>"
$PN"205"29;
"DQ<17>"
$PN"172"81;
"DQ<15>"
$PN"166"82;
"DQ<26>"
$PN"45"92;
"DQ<27>"
$PN"190"93;
"S0_N"
$PN"84"40;
"CKE<0>"
$PN"60"41;
"ODT<1>"
$PN"91"42;
"ODT<0>"
$PN"87"43;
"CB<7>"
$PN"199"44;
"A16_RAS_N"
$PN"82"122;
"A15_CAS_N"
$PN"86"123;
"A14_WE_N"
$PN"228"124;
"A11"
$PN"210"125;
"A10"
$PN"225"126;
"DQ<38>"
$PN"102"102;
"DQ<36>"
$PN"95"103;
"DQ<35>"
$PN"249"104;
"A2"
$PN"216"45;
"ALERT_N"
$PN"208"31;
"ACT_N"
$PN"62"32;
"DQ<0>"
$PN"5"70;
"DQ<1>"
$PN"150"75;
"SA<1>"
$PN"140"16;
"SA<2>"
$PN"238"19;
"VDDSPD"
$PN"284"19;
"SA<0>"
$PN"139"16;
"BA<0>"
$PN"81"46;
"BG<1>"
$PN"207"47;
"BG<0>"
$PN"63"48;
"CK1P"
$PN"218"66;
"VREFCA"
$PN"146"27;
"SDA"
$PN"285"34;
"SCL"
$PN"141"33;
"RFU<2>"
$PN"144"30;
"RESET_N"
$PN"58"37;
"PAR"
$PN"222"38;
"EVENT_N"
$PN"78"36;
"DQ<6>"
$PN"10"76;
"DQ<7>"
$PN"155"77;
"DQ<8>"
$PN"16"78;
"DQ<9>"
$PN"161"79;
"DQ<10>"
$PN"23"80;
"DQ<11>"
$PN"168"83;
"DQ<12>"
$PN"14"84;
"DQ<13>"
$PN"159"85;
"DQ<14>"
$PN"21"86;
"DQ<16>"
$PN"27"87;
"DQ<18>"
$PN"34"88;
"DQ<19>"
$PN"179"89;
"DQ<20>"
$PN"25"90;
"DQ<21>"
$PN"170"91;
"DQ<22>"
$PN"32"94;
"DQ<23>"
$PN"177"95;
"DQ<24>"
$PN"38"96;
"DQ<25>"
$PN"183"97;
"DQ<30>"
$PN"43"98;
"DQ<31>"
$PN"188"99;
"DQ<32>"
$PN"97"105;
"DQ<33>"
$PN"242"106;
"DQ<34>"
$PN"104"107;
"DQ<37>"
$PN"240"108;
"DQ<39>"
$PN"247"109;
"DQ<40>"
$PN"108"110;
"DQ<41>"
$PN"253"111;
"DQ<42>"
$PN"115"117;
"DQ<43>"
$PN"260"118;
"DQ<44>"
$PN"106"119;
"DQ<45>"
$PN"251"120;
"DQ<46>"
$PN"113"121;
"DQ<55>"
$PN"269"137;
"DQ<56>"
$PN"130"138;
"DQ<59>"
$PN"282"139;
"DQ<60>"
$PN"128"140;
"CKE<1>"
$PN"203"49;
"CK0N"
$PN"75"67;
"CB<0>"
$PN"49"50;
"CB<1>"
$PN"194"51;
"CB<2>"
$PN"56"52;
"CB<3>"
$PN"201"53;
"CB<4>"
$PN"47"54;
"CB<5>"
$PN"192"55;
"CB<6>"
$PN"54"56;
"A9"
$PN"66"127;
"A8"
$PN"68"128;
"A7"
$PN"211"24;
"A6"
$PN"69"25;
"A5"
$PN"213"57;
"A4"
$PN"214"58;
"A3"
$PN"71"59;
"A17"
$PN"234"129;
"A13"
$PN"232"23;
"A12"
$PN"65"130;
"A1"
$PN"72"60;
"A0"
$PN"79"61;
"C<2>"
$PN"235"39;
"DQ<28>"
$PN"36"100;
"DQ<29>"
$PN"181"101;
"S1_N"
$PN"89"62;
"S2_N_C<0>"
$PN"93"63;
"S3_N_C<1>"
$PN"237"64;
"CK0P"
$PN"74"68;
"CK1N"
$PN"219"69;
"BA<1>"
$PN"224"65;
%"TAP"
"6","(-3200,4650)","0","mstr_standard","I112";
;
CDS_LIB"mstr_standard"
BODY_TYPE"PLUMBING"
HDL_TAP"TRUE";
"B \NAC \NWC"4;
"S \NAC"
BN"17"129;
%"TAP"
"6","(-3200,4600)","0","mstr_standard","I113";
;
CDS_LIB"mstr_standard"
BODY_TYPE"PLUMBING"
HDL_TAP"TRUE";
"B \NAC \NWC"4;
"S \NAC"
BN"16"122;
%"TAP"
"6","(-3200,4550)","0","mstr_standard","I114";
;
CDS_LIB"mstr_standard"
BODY_TYPE"PLUMBING"
HDL_TAP"TRUE";
"B \NAC \NWC"4;
"S \NAC"
BN"15"123;
%"TAP"
"6","(-3200,4500)","0","mstr_standard","I115";
;
CDS_LIB"mstr_standard"
BODY_TYPE"PLUMBING"
HDL_TAP"TRUE";
"B \NAC \NWC"4;
"S \NAC"
BN"14"124;
%"TAP"
"6","(-3200,4450)","0","mstr_standard","I116";
;
CDS_LIB"mstr_standard"
BODY_TYPE"PLUMBING"
HDL_TAP"TRUE";
"B \NAC \NWC"4;
"S \NAC"
BN"13"23;
%"TAP"
"6","(-3200,4400)","0","mstr_standard","I117";
;
CDS_LIB"mstr_standard"
BODY_TYPE"PLUMBING"
HDL_TAP"TRUE";
"B \NAC \NWC"4;
"S \NAC"
BN"12"130;
%"TAP"
"6","(-3200,4350)","0","mstr_standard","I118";
;
CDS_LIB"mstr_standard"
BODY_TYPE"PLUMBING"
HDL_TAP"TRUE";
"B \NAC \NWC"4;
"S \NAC"
BN"11"125;
%"TAP"
"6","(-3200,4300)","0","mstr_standard","I119";
;
CDS_LIB"mstr_standard"
BODY_TYPE"PLUMBING"
HDL_TAP"TRUE";
"B \NAC \NWC"4;
"S \NAC"
BN"10"126;
%"PVTT_ABC"
"1","(-850,2700)","0","mstr_symbols","I12";
;
VOLTAGE"0.6V"
BOM_COST"MEM"
CDS_LIB"mstr_symbols"
BODY_TYPE"PLUMBING"
ROOM"DDR4_CH_A"
HDL_POWER"PVTT_ABC";
"G\NAC"13;
%"TAP"
"6","(-3200,4250)","0","mstr_standard","I120";
;
CDS_LIB"mstr_standard"
BODY_TYPE"PLUMBING"
HDL_TAP"TRUE";
"B \NAC \NWC"4;
"S \NAC"
BN"9"127;
%"TAP"
"6","(-3200,4200)","0","mstr_standard","I121";
;
CDS_LIB"mstr_standard"
BODY_TYPE"PLUMBING"
HDL_TAP"TRUE";
"B \NAC \NWC"4;
"S \NAC"
BN"8"128;
%"TAP"
"6","(-3200,4150)","0","mstr_standard","I122";
;
CDS_LIB"mstr_standard"
BODY_TYPE"PLUMBING"
HDL_TAP"TRUE";
"B \NAC \NWC"4;
"S \NAC"
BN"7"24;
%"TAP"
"6","(-3200,4100)","0","mstr_standard","I123";
;
CDS_LIB"mstr_standard"
BODY_TYPE"PLUMBING"
HDL_TAP"TRUE";
"B \NAC \NWC"4;
"S \NAC"
BN"6"25;
%"TAP"
"6","(-3200,4050)","0","mstr_standard","I124";
;
CDS_LIB"mstr_standard"
BODY_TYPE"PLUMBING"
HDL_TAP"TRUE";
"B \NAC \NWC"4;
"S \NAC"
BN"5"57;
%"TAP"
"6","(-3200,4000)","0","mstr_standard","I125";
;
CDS_LIB"mstr_standard"
BODY_TYPE"PLUMBING"
HDL_TAP"TRUE";
"B \NAC \NWC"4;
"S \NAC"
BN"4"58;
%"TAP"
"6","(-3200,3950)","0","mstr_standard","I126";
;
CDS_LIB"mstr_standard"
BODY_TYPE"PLUMBING"
HDL_TAP"TRUE";
"B \NAC \NWC"4;
"S \NAC"
BN"3"59;
%"TAP"
"6","(-3200,3900)","0","mstr_standard","I128";
;
CDS_LIB"mstr_standard"
BODY_TYPE"PLUMBING"
HDL_TAP"TRUE";
"B \NAC \NWC"4;
"S \NAC"
BN"2"45;
%"TAP"
"6","(-3200,3850)","0","mstr_standard","I129";
;
CDS_LIB"mstr_standard"
BODY_TYPE"PLUMBING"
HDL_TAP"TRUE";
"B \NAC \NWC"4;
"S \NAC"
BN"1"60;
%"PVDDQ_ABC"
"1","(-1150,2600)","0","mstr_symbols","I13";
;
VOLTAGE"1.2V"
BOM_COST"MEM"
CDS_LIB"mstr_symbols"
BODY_TYPE"PLUMBING"
ROOM"DDR4_CH_A"
HDL_POWER"PVDDQ_ABC";
"G\NAC"14;
%"TAP"
"6","(-3200,3800)","0","mstr_standard","I130";
;
CDS_LIB"mstr_standard"
BODY_TYPE"PLUMBING"
HDL_TAP"TRUE";
"B \NAC \NWC"4;
"S \NAC"
BN"0"61;
%"TAP"
"6","(-3200,3700)","0","mstr_standard","I131";
;
CDS_LIB"mstr_standard"
BODY_TYPE"PLUMBING"
HDL_TAP"TRUE";
"B \NAC \NWC"7;
"S \NAC"
BN"1"65;
%"TAP"
"6","(-3200,3650)","0","mstr_standard","I132";
;
CDS_LIB"mstr_standard"
BODY_TYPE"PLUMBING"
HDL_TAP"TRUE";
"B \NAC \NWC"7;
"S \NAC"
BN"0"46;
%"TAP"
"6","(-3200,3550)","0","mstr_standard","I133";
;
CDS_LIB"mstr_standard"
BODY_TYPE"PLUMBING"
HDL_TAP"TRUE";
"B \NAC \NWC"11;
"S \NAC"
BN"0"48;
%"TAP"
"6","(-3200,3600)","0","mstr_standard","I134";
;
CDS_LIB"mstr_standard"
BODY_TYPE"PLUMBING"
HDL_TAP"TRUE";
"B \NAC \NWC"11;
"S \NAC"
BN"1"47;
%"TAP"
"6","(-3200,2600)","0","mstr_standard","I138";
;
CDS_LIB"mstr_standard"
BODY_TYPE"PLUMBING"
HDL_TAP"TRUE";
"B \NAC \NWC"9;
"S \NAC"
BN"6"44;
%"TAP"
"6","(-3200,2550)","0","mstr_standard","I139";
;
CDS_LIB"mstr_standard"
BODY_TYPE"PLUMBING"
HDL_TAP"TRUE";
"B \NAC \NWC"9;
"S \NAC"
BN"7"56;
%"TAP"
"6","(900,4650)","2","mstr_standard","I14";
;
CDS_LIB"mstr_standard"
BODY_TYPE"PLUMBING"
HDL_TAP"TRUE";
"B \NAC \NWC"1;
"S \NAC"
BN"12"170;
%"TAP"
"6","(-3200,2500)","0","mstr_standard","I140";
;
CDS_LIB"mstr_standard"
BODY_TYPE"PLUMBING"
HDL_TAP"TRUE";
"B \NAC \NWC"9;
"S \NAC"
BN"4"55;
%"TAP"
"6","(-3200,2450)","0","mstr_standard","I141";
;
CDS_LIB"mstr_standard"
BODY_TYPE"PLUMBING"
HDL_TAP"TRUE";
"B \NAC \NWC"9;
"S \NAC"
BN"5"54;
%"TAP"
"6","(-3200,2400)","0","mstr_standard","I142";
;
CDS_LIB"mstr_standard"
BODY_TYPE"PLUMBING"
HDL_TAP"TRUE";
"B \NAC \NWC"9;
"S \NAC"
BN"2"53;
%"TAP"
"6","(-3200,2350)","0","mstr_standard","I143";
;
CDS_LIB"mstr_standard"
BODY_TYPE"PLUMBING"
HDL_TAP"TRUE";
"B \NAC \NWC"9;
"S \NAC"
BN"3"52;
%"TAP"
"6","(-3200,2300)","0","mstr_standard","I144";
;
CDS_LIB"mstr_standard"
BODY_TYPE"PLUMBING"
HDL_TAP"TRUE";
"B \NAC \NWC"9;
"S \NAC"
BN"0"51;
%"TAP"
"6","(-3200,2250)","0","mstr_standard","I145";
;
CDS_LIB"mstr_standard"
BODY_TYPE"PLUMBING"
HDL_TAP"TRUE";
"B \NAC \NWC"9;
"S \NAC"
BN"1"50;
%"TAP"
"6","(900,4750)","2","mstr_standard","I15";
;
CDS_LIB"mstr_standard"
BODY_TYPE"PLUMBING"
HDL_TAP"TRUE";
"B \NAC \NWC"1;
"S \NAC"
BN"13"26;
%"TAP"
"6","(-3200,2700)","0","mstr_standard","I152";
;
CDS_LIB"mstr_standard"
BODY_TYPE"PLUMBING"
HDL_TAP"TRUE";
"B \NAC \NWC"12;
"S \NAC"
BN"0"43;
%"TAP"
"6","(-3200,2750)","0","mstr_standard","I153";
;
CDS_LIB"mstr_standard"
BODY_TYPE"PLUMBING"
HDL_TAP"TRUE";
"B \NAC \NWC"12;
"S \NAC"
BN"1"42;
%"TAP"
"6","(-3200,2900)","0","mstr_standard","I155";
;
CDS_LIB"mstr_standard"
BODY_TYPE"PLUMBING"
HDL_TAP"TRUE";
"B \NAC \NWC"10;
"S \NAC"
BN"1"49;
%"TAP"
"6","(-3200,2850)","0","mstr_standard","I156";
;
CDS_LIB"mstr_standard"
BODY_TYPE"PLUMBING"
HDL_TAP"TRUE";
"B \NAC \NWC"10;
"S \NAC"
BN"0"41;
%"TAP"
"6","(-3200,3150)","0","mstr_standard","I158";
;
CDS_LIB"mstr_standard"
BODY_TYPE"PLUMBING"
HDL_TAP"TRUE";
"B \NAC \NWC"8;
"S \NAC"
BN"3"64;
%"TAP"
"6","(700,4800)","2","mstr_standard","I16";
;
CDS_LIB"mstr_standard"
BODY_TYPE"PLUMBING"
HDL_TAP"TRUE";
"B \NAC \NWC"2;
"S \NAC"
BN"13"168;
%"TAP"
"6","(-3200,3100)","0","mstr_standard","I160";
;
CDS_LIB"mstr_standard"
BODY_TYPE"PLUMBING"
HDL_TAP"TRUE";
"B \NAC \NWC"8;
"S \NAC"
BN"2"63;
%"TAP"
"6","(-3200,3050)","0","mstr_standard","I161";
;
CDS_LIB"mstr_standard"
BODY_TYPE"PLUMBING"
HDL_TAP"TRUE";
"B \NAC \NWC"8;
"S \NAC"
BN"1"62;
%"TAP"
"6","(-3200,3000)","0","mstr_standard","I162";
;
CDS_LIB"mstr_standard"
BODY_TYPE"PLUMBING"
HDL_TAP"TRUE";
"B \NAC \NWC"8;
"S \NAC"
BN"0"40;
%"TAP"
"6","(700,4700)","2","mstr_standard","I17";
;
CDS_LIB"mstr_standard"
BODY_TYPE"PLUMBING"
HDL_TAP"TRUE";
"B \NAC \NWC"2;
"S \NAC"
BN"12"169;
%"TAP"
"6","(-3750,3300)","0","mstr_standard","I174";
;
CDS_LIB"mstr_standard"
BODY_TYPE"PLUMBING"
HDL_TAP"TRUE";
"B \NAC \NWC"5;
"S \NAC"
BN"0"67;
%"TAP"
"6","(-3600,3350)","0","mstr_standard","I175";
;
CDS_LIB"mstr_standard"
BODY_TYPE"PLUMBING"
HDL_TAP"TRUE";
"B \NAC \NWC"6;
"S \NAC"
BN"0"68;
%"SCONN288_H44441004"
"4","(0,2050)","0","mstr_sconn","I179";
;
CDS_SEC"4"
LOCATION"J4G3"
PART_NUMBER"H44441-004"
MATERIAL"SCONN"
PACK_TYPE"PIP"
BOM_COST"MEM"
CDS_LIB"mstr_sconn"
SEC_TYPE"PIP"
SEC"4"
CDS_LOCATION"J4G3"
ROOM"DDR4_CH_C";
"VPP<4>"
$PN"142"18;
"VTT<1>"
$PN"77"13;
"VPP<0>"
$PN"287"18;
"VPP<1>"
$PN"286"18;
"VPP<2>"
$PN"288"18;
"VPP<3>"
$PN"143"18;
"VDD<1>"
$PN"233"14;
"VDD<2>"
$PN"231"14;
"VDD<3>"
$PN"229"14;
"VDD<4>"
$PN"226"14;
"VDD<5>"
$PN"223"14;
"VDD<7>"
$PN"217"14;
"VDD<8>"
$PN"215"14;
"VDD<9>"
$PN"212"14;
"VDD<11>"
$PN"206"14;
"VDD<12>"
$PN"204"14;
"VDD<14>"
$PN"90"14;
"VDD<15>"
$PN"88"14;
"VDD<17>"
$PN"83"14;
"VDD<18>"
$PN"80"14;
"VDD<20>"
$PN"73"14;
"VDD<21>"
$PN"70"14;
"VDD<22>"
$PN"67"14;
"VDD<24>"
$PN"61"14;
"12V<0>"
$PN"145"20;
"12V<1>"
$PN"1"20;
"VTT<0>"
$PN"221"13;
"VDD<25>"
$PN"59"14;
"VDD<23>"
$PN"64"14;
"VDD<19>"
$PN"76"14;
"VDD<16>"
$PN"85"14;
"VDD<13>"
$PN"92"14;
"VDD<10>"
$PN"209"14;
"VDD<6>"
$PN"220"14;
"VDD<0>"
$PN"236"14;
%"TAP"
"6","(700,4600)","2","mstr_standard","I18";
;
CDS_LIB"mstr_standard"
BODY_TYPE"PLUMBING"
HDL_TAP"TRUE";
"B \NAC \NWC"2;
"S \NAC"
BN"11"171;
%"GND"
"1","(2500,1350)","2","mstr_symbols","I180";
;
VOLTAGE"0"
SIZE"1B"
CDS_LIB"mstr_symbols"
BOM_COST"MEM"
BODY_TYPE"PLUMBING"
ROOM"DDR4_CH_A"
HDL_POWER"GND";
"A\NAC"15;
%"GND"
"1","(-4950,1650)","2","mstr_symbols","I184";
;
VOLTAGE"0"
BOM_COST"MEM"
CDS_LIB"mstr_symbols"
SIZE"1B"
BODY_TYPE"PLUMBING"
ROOM"DDR4_CH_A"
HDL_POWER"GND";
"A\NAC"16;
%"CAP_A"
"1","(-4650,1300)","2","dev_discrete","I188";
;
LOCATION"C4G19"
PART_NUMBER"A36096-045"
VALUE"0.01UF"
TOLERANCE"10%"
PACK_TYPE"0402V"
VOLTAGE"25V"
MATERIAL"X7R"
CDS_LOCATION"C4G19"
BOM_COST"MEM"
CDS_LIB"dev_discrete"
CDS_SEC"1"
SEC_TYPE"0402V"
SEC"1"
ROOM"DDR4_CH_C";
"B"
$PN"2"17;
"A"
$PN"1"27;
%"GND"
"1","(-4650,1050)","0","mstr_symbols","I189";
;
VOLTAGE"0"
BOM_COST"MEM"
CDS_LIB"mstr_symbols"
SIZE"1B"
BODY_TYPE"PLUMBING"
ROOM"DDR4_CH_A"
HDL_POWER"GND";
"A\NAC"17;
%"TAP"
"6","(900,4450)","2","mstr_standard","I19";
;
CDS_LIB"mstr_standard"
BODY_TYPE"PLUMBING"
HDL_TAP"TRUE";
"B \NAC \NWC"1;
"S \NAC"
BN"10"174;
%"PVPP_ABC"
"1","(-700,3050)","0","mstr_symbols","I190";
;
VOLTAGE"2.5V"
BOM_COST"MEM"
CDS_LIB"mstr_symbols"
BODY_TYPE"PLUMBING"
ROOM"DDR4_CH_A"
HDL_POWER"PVPP_ABC";
"G\NAC"18;
%"PVPP_ABC"
"1","(-4950,2000)","0","mstr_symbols","I191";
;
VOLTAGE"2.5V"
BOM_COST"MEM"
CDS_LIB"mstr_symbols"
BODY_TYPE"PLUMBING"
ROOM"DDR4_CH_A"
HDL_POWER"PVPP_ABC";
"G\NAC"19;
%"TAP"
"6","(-3600,3450)","0","mstr_standard","I196";
;
CDS_LIB"mstr_standard"
BODY_TYPE"PLUMBING"
HDL_TAP"TRUE";
"B \NAC \NWC"6;
"S \NAC"
BN"1"66;
%"TAP"
"6","(-3750,3400)","0","mstr_standard","I197";
;
CDS_LIB"mstr_standard"
BODY_TYPE"PLUMBING"
HDL_TAP"TRUE";
"B \NAC \NWC"5;
"S \NAC"
BN"1"69;
%"P12V_NVDIMM_ABC"
"1","(700,3125)","0","mstr_symbols","I198";
;
VOLTAGE"12.0"
CDS_LIB"mstr_symbols"
BODY_TYPE"PLUMBING"
HDL_POWER"P12V_NVDIMM_ABC";
"G\NAC"20;
%"TAP"
"6","(900,4550)","2","mstr_standard","I20";
;
CDS_LIB"mstr_standard"
BODY_TYPE"PLUMBING"
HDL_TAP"TRUE";
"B \NAC \NWC"1;
"S \NAC"
BN"11"172;
%"TAP"
"6","(900,4350)","2","mstr_standard","I21";
;
CDS_LIB"mstr_standard"
BODY_TYPE"PLUMBING"
HDL_TAP"TRUE";
"B \NAC \NWC"1;
"S \NAC"
BN"9"156;
%"TAP"
"6","(700,4500)","2","mstr_standard","I22";
;
CDS_LIB"mstr_standard"
BODY_TYPE"PLUMBING"
HDL_TAP"TRUE";
"B \NAC \NWC"2;
"S \NAC"
BN"10"173;
%"TAP"
"6","(700,4400)","2","mstr_standard","I23";
;
CDS_LIB"mstr_standard"
BODY_TYPE"PLUMBING"
HDL_TAP"TRUE";
"B \NAC \NWC"2;
"S \NAC"
BN"9"155;
%"TAP"
"6","(900,4150)","2","mstr_standard","I24";
;
CDS_LIB"mstr_standard"
BODY_TYPE"PLUMBING"
HDL_TAP"TRUE";
"B \NAC \NWC"1;
"S \NAC"
BN"7"160;
%"TAP"
"6","(900,4250)","2","mstr_standard","I25";
;
CDS_LIB"mstr_standard"
BODY_TYPE"PLUMBING"
HDL_TAP"TRUE";
"B \NAC \NWC"1;
"S \NAC"
BN"8"158;
%"TAP"
"6","(700,4300)","2","mstr_standard","I26";
;
CDS_LIB"mstr_standard"
BODY_TYPE"PLUMBING"
HDL_TAP"TRUE";
"B \NAC \NWC"2;
"S \NAC"
BN"8"157;
%"TAP"
"6","(700,4200)","2","mstr_standard","I27";
;
CDS_LIB"mstr_standard"
BODY_TYPE"PLUMBING"
HDL_TAP"TRUE";
"B \NAC \NWC"2;
"S \NAC"
BN"7"159;
%"TAP"
"6","(700,4100)","2","mstr_standard","I28";
;
CDS_LIB"mstr_standard"
BODY_TYPE"PLUMBING"
HDL_TAP"TRUE";
"B \NAC \NWC"2;
"S \NAC"
BN"6"161;
%"TAP"
"6","(900,3950)","2","mstr_standard","I29";
;
CDS_LIB"mstr_standard"
BODY_TYPE"PLUMBING"
HDL_TAP"TRUE";
"B \NAC \NWC"1;
"S \NAC"
BN"5"144;
%"TAP"
"6","(900,5150)","2","mstr_standard","I3";
;
CDS_LIB"mstr_standard"
BODY_TYPE"PLUMBING"
HDL_TAP"TRUE";
"B \NAC \NWC"1;
"S \NAC"
BN"17"176;
%"TAP"
"6","(900,4050)","2","mstr_standard","I30";
;
CDS_LIB"mstr_standard"
BODY_TYPE"PLUMBING"
HDL_TAP"TRUE";
"B \NAC \NWC"1;
"S \NAC"
BN"6"142;
%"TAP"
"6","(900,3850)","2","mstr_standard","I31";
;
CDS_LIB"mstr_standard"
BODY_TYPE"PLUMBING"
HDL_TAP"TRUE";
"B \NAC \NWC"1;
"S \NAC"
BN"4"146;
%"TAP"
"6","(700,4000)","2","mstr_standard","I32";
;
CDS_LIB"mstr_standard"
BODY_TYPE"PLUMBING"
HDL_TAP"TRUE";
"B \NAC \NWC"2;
"S \NAC"
BN"5"143;
%"TAP"
"6","(700,3900)","2","mstr_standard","I33";
;
CDS_LIB"mstr_standard"
BODY_TYPE"PLUMBING"
HDL_TAP"TRUE";
"B \NAC \NWC"2;
"S \NAC"
BN"4"145;
%"TAP"
"6","(700,3800)","2","mstr_standard","I34";
;
CDS_LIB"mstr_standard"
BODY_TYPE"PLUMBING"
HDL_TAP"TRUE";
"B \NAC \NWC"2;
"S \NAC"
BN"3"147;
%"TAP"
"6","(900,3550)","2","mstr_standard","I35";
;
CDS_LIB"mstr_standard"
BODY_TYPE"PLUMBING"
HDL_TAP"TRUE";
"B \NAC \NWC"1;
"S \NAC"
BN"1"152;
%"TAP"
"6","(900,3650)","2","mstr_standard","I36";
;
CDS_LIB"mstr_standard"
BODY_TYPE"PLUMBING"
HDL_TAP"TRUE";
"B \NAC \NWC"1;
"S \NAC"
BN"2"150;
%"TAP"
"6","(900,3750)","2","mstr_standard","I37";
;
CDS_LIB"mstr_standard"
BODY_TYPE"PLUMBING"
HDL_TAP"TRUE";
"B \NAC \NWC"1;
"S \NAC"
BN"3"148;
%"TAP"
"6","(700,3700)","2","mstr_standard","I38";
;
CDS_LIB"mstr_standard"
BODY_TYPE"PLUMBING"
HDL_TAP"TRUE";
"B \NAC \NWC"2;
"S \NAC"
BN"2"149;
%"TAP"
"6","(700,3600)","2","mstr_standard","I39";
;
CDS_LIB"mstr_standard"
BODY_TYPE"PLUMBING"
HDL_TAP"TRUE";
"B \NAC \NWC"2;
"S \NAC"
BN"1"151;
%"TAP"
"6","(700,5200)","2","mstr_standard","I4";
;
CDS_LIB"mstr_standard"
BODY_TYPE"PLUMBING"
HDL_TAP"TRUE";
"B \NAC \NWC"2;
"S \NAC"
BN"17"175;
%"TAP"
"6","(900,3450)","2","mstr_standard","I40";
;
CDS_LIB"mstr_standard"
BODY_TYPE"PLUMBING"
HDL_TAP"TRUE";
"B \NAC \NWC"1;
"S \NAC"
BN"0"154;
%"TAP"
"6","(700,3500)","2","mstr_standard","I41";
;
CDS_LIB"mstr_standard"
BODY_TYPE"PLUMBING"
HDL_TAP"TRUE";
"B \NAC \NWC"2;
"S \NAC"
BN"0"153;
%"SCONN288_H44441004"
"3","(1800,2650)","0","mstr_sconn","I43";
;
CDS_SEC"3"
LOCATION"J4G3"
PART_NUMBER"H44441-004"
MATERIAL"SCONN"
PACK_TYPE"PIP"
BOM_COST"MEM"
CDS_LIB"mstr_sconn"
SEC_TYPE"PIP"
SEC"3"
CDS_LOCATION"J4G3"
ROOM"DDR4_CH_C";
"VSS<93>"
$PN"2"21;
"VSS<92>"
$PN"4"21;
"VSS<91>"
$PN"6"21;
"VSS<90>"
$PN"9"21;
"VSS<89>"
$PN"11"21;
"VSS<88>"
$PN"13"21;
"VSS<0>"
$PN"283"15;
"VSS<1>"
$PN"281"15;
"VSS<2>"
$PN"279"15;
"VSS<3>"
$PN"276"15;
"VSS<4>"
$PN"274"15;
"VSS<5>"
$PN"272"15;
"VSS<6>"
$PN"270"15;
"VSS<7>"
$PN"268"15;
"VSS<8>"
$PN"265"15;
"VSS<9>"
$PN"263"15;
"VSS<10>"
$PN"261"15;
"VSS<11>"
$PN"259"15;
"VSS<12>"
$PN"257"15;
"VSS<13>"
$PN"254"15;
"VSS<14>"
$PN"252"15;
"VSS<15>"
$PN"250"15;
"VSS<16>"
$PN"248"15;
"VSS<17>"
$PN"246"15;
"VSS<18>"
$PN"243"15;
"VSS<19>"
$PN"241"15;
"VSS<20>"
$PN"239"15;
"VSS<21>"
$PN"202"15;
"VSS<22>"
$PN"200"15;
"VSS<23>"
$PN"198"15;
"VSS<24>"
$PN"195"15;
"VSS<25>"
$PN"193"15;
"VSS<26>"
$PN"191"15;
"VSS<27>"
$PN"189"15;
"VSS<28>"
$PN"187"15;
"VSS<29>"
$PN"184"15;
"VSS<30>"
$PN"182"15;
"VSS<31>"
$PN"180"15;
"VSS<32>"
$PN"178"15;
"VSS<33>"
$PN"176"15;
"VSS<34>"
$PN"173"15;
"VSS<35>"
$PN"171"15;
"VSS<36>"
$PN"169"15;
"VSS<37>"
$PN"167"15;
"VSS<38>"
$PN"165"15;
"VSS<39>"
$PN"162"15;
"VSS<40>"
$PN"160"15;
"VSS<41>"
$PN"158"15;
"VSS<42>"
$PN"156"15;
"VSS<43>"
$PN"154"15;
"VSS<44>"
$PN"151"15;
"VSS<47>"
$PN"138"21;
"VSS<48>"
$PN"136"21;
"VSS<49>"
$PN"134"21;
"VSS<50>"
$PN"131"21;
"VSS<51>"
$PN"129"21;
"VSS<52>"
$PN"127"21;
"VSS<53>"
$PN"125"21;
"VSS<54>"
$PN"123"21;
"VSS<55>"
$PN"120"21;
"VSS<56>"
$PN"118"21;
"VSS<57>"
$PN"116"21;
"VSS<58>"
$PN"114"21;
"VSS<59>"
$PN"112"21;
"VSS<60>"
$PN"109"21;
"VSS<61>"
$PN"107"21;
"VSS<62>"
$PN"105"21;
"VSS<63>"
$PN"103"21;
"VSS<64>"
$PN"101"21;
"VSS<65>"
$PN"98"21;
"VSS<66>"
$PN"96"21;
"VSS<67>"
$PN"94"21;
"VSS<68>"
$PN"57"21;
"VSS<69>"
$PN"55"21;
"VSS<70>"
$PN"53"21;
"VSS<71>"
$PN"50"21;
"VSS<72>"
$PN"48"21;
"VSS<73>"
$PN"46"21;
"VSS<74>"
$PN"44"21;
"VSS<75>"
$PN"42"21;
"VSS<76>"
$PN"39"21;
"VSS<77>"
$PN"37"21;
"VSS<78>"
$PN"35"21;
"VSS<79>"
$PN"33"21;
"VSS<80>"
$PN"31"21;
"VSS<81>"
$PN"28"21;
"VSS<82>"
$PN"26"21;
"VSS<83>"
$PN"24"21;
"VSS<84>"
$PN"22"21;
"VSS<85>"
$PN"20"21;
"VSS<86>"
$PN"17"21;
"VSS<87>"
$PN"15"21;
"VSS<45>"
$PN"149"15;
"VSS<46>"
$PN"147"15;
%"GND"
"1","(1100,1350)","2","mstr_symbols","I44";
;
VOLTAGE"0"
CDS_LIB"mstr_symbols"
SIZE"1B"
BOM_COST"MEM"
BODY_TYPE"PLUMBING"
ROOM"DDR4_CH_A"
HDL_POWER"GND";
"A\NAC"21;
%"TAP"
"6","(-1700,4650)","2","mstr_standard","I46";
;
CDS_LIB"mstr_standard"
BODY_TYPE"PLUMBING"
HDL_TAP"TRUE";
"B \NAC \NWC"3;
"S \NAC"
BN"62"141;
%"TAP"
"6","(-1700,4600)","2","mstr_standard","I47";
;
CDS_LIB"mstr_standard"
BODY_TYPE"PLUMBING"
HDL_TAP"TRUE";
"B \NAC \NWC"3;
"S \NAC"
BN"63"131;
%"TAP"
"6","(-1700,4450)","2","mstr_standard","I48";
;
CDS_LIB"mstr_standard"
BODY_TYPE"PLUMBING"
HDL_TAP"TRUE";
"B \NAC \NWC"3;
"S \NAC"
BN"58"139;
%"TAP"
"6","(-1700,4500)","2","mstr_standard","I49";
;
CDS_LIB"mstr_standard"
BODY_TYPE"PLUMBING"
HDL_TAP"TRUE";
"B \NAC \NWC"3;
"S \NAC"
BN"61"140;
%"TAP"
"6","(700,5100)","2","mstr_standard","I5";
;
CDS_LIB"mstr_standard"
BODY_TYPE"PLUMBING"
HDL_TAP"TRUE";
"B \NAC \NWC"2;
"S \NAC"
BN"16"162;
%"TAP"
"6","(-1700,4550)","2","mstr_standard","I50";
;
CDS_LIB"mstr_standard"
BODY_TYPE"PLUMBING"
HDL_TAP"TRUE";
"B \NAC \NWC"3;
"S \NAC"
BN"60"132;
%"TAP"
"6","(-1700,4350)","2","mstr_standard","I51";
;
CDS_LIB"mstr_standard"
BODY_TYPE"PLUMBING"
HDL_TAP"TRUE";
"B \NAC \NWC"3;
"S \NAC"
BN"56"22;
%"TAP"
"6","(-1700,4400)","2","mstr_standard","I52";
;
CDS_LIB"mstr_standard"
BODY_TYPE"PLUMBING"
HDL_TAP"TRUE";
"B \NAC \NWC"3;
"S \NAC"
BN"59"136;
%"TAP"
"6","(-1700,4200)","2","mstr_standard","I53";
;
CDS_LIB"mstr_standard"
BODY_TYPE"PLUMBING"
HDL_TAP"TRUE";
"B \NAC \NWC"3;
"S \NAC"
BN"55"135;
%"TAP"
"6","(-1700,4250)","2","mstr_standard","I54";
;
CDS_LIB"mstr_standard"
BODY_TYPE"PLUMBING"
HDL_TAP"TRUE";
"B \NAC \NWC"3;
"S \NAC"
BN"54"137;
%"TAP"
"6","(-1700,4300)","2","mstr_standard","I55";
;
CDS_LIB"mstr_standard"
BODY_TYPE"PLUMBING"
HDL_TAP"TRUE";
"B \NAC \NWC"3;
"S \NAC"
BN"57"138;
%"TAP"
"6","(-1700,4100)","2","mstr_standard","I56";
;
CDS_LIB"mstr_standard"
BODY_TYPE"PLUMBING"
HDL_TAP"TRUE";
"B \NAC \NWC"3;
"S \NAC"
BN"53"133;
%"TAP"
"6","(-1700,4150)","2","mstr_standard","I57";
;
CDS_LIB"mstr_standard"
BODY_TYPE"PLUMBING"
HDL_TAP"TRUE";
"B \NAC \NWC"3;
"S \NAC"
BN"52"134;
%"TAP"
"6","(-1700,4050)","2","mstr_standard","I58";
;
CDS_LIB"mstr_standard"
BODY_TYPE"PLUMBING"
HDL_TAP"TRUE";
"B \NAC \NWC"3;
"S \NAC"
BN"50"116;
%"TAP"
"6","(-1700,4000)","2","mstr_standard","I59";
;
CDS_LIB"mstr_standard"
BODY_TYPE"PLUMBING"
HDL_TAP"TRUE";
"B \NAC \NWC"3;
"S \NAC"
BN"51"115;
%"TAP"
"6","(900,4950)","2","mstr_standard","I6";
;
CDS_LIB"mstr_standard"
BODY_TYPE"PLUMBING"
HDL_TAP"TRUE";
"B \NAC \NWC"1;
"S \NAC"
BN"15"165;
%"TAP"
"6","(-1700,3950)","2","mstr_standard","I60";
;
CDS_LIB"mstr_standard"
BODY_TYPE"PLUMBING"
HDL_TAP"TRUE";
"B \NAC \NWC"3;
"S \NAC"
BN"48"114;
%"SCONN288_H44441004"
"2","(0,4350)","0","mstr_sconn","I61";
;
CDS_SEC"2"
LOCATION"J4G3"
PART_NUMBER"H44441-004"
MATERIAL"SCONN"
PACK_TYPE"PIP"
BOM_COST"MEM"
CDS_LIB"mstr_sconn"
SEC_TYPE"PIP"
SEC"2"
CDS_LOCATION"J4G3"
ROOM"DDR4_CH_C";
"DQS17P"
$PN"51"175;
"DQS9P"
$PN"7"155;
"DQS9N"
$PN"8"156;
"DQS8P"
$PN"197"157;
"DQS8N"
$PN"196"158;
"DQS7P"
$PN"278"159;
"DQS7N"
$PN"277"160;
"DQS6P"
$PN"267"161;
"DQS6N"
$PN"266"142;
"DQS5P"
$PN"256"143;
"DQS5N"
$PN"255"144;
"DQS4P"
$PN"245"145;
"DQS4N"
$PN"244"146;
"DQS3P"
$PN"186"147;
"DQS3N"
$PN"185"148;
"DQS2P"
$PN"175"149;
"DQS2N"
$PN"174"150;
"DQS1P"
$PN"164"151;
"DQS1N"
$PN"163"152;
"DQS17N"
$PN"52"176;
"DQS16P"
$PN"132"162;
"DQS16N"
$PN"133"163;
"DQS15P"
$PN"121"164;
"DQS15N"
$PN"122"165;
"DQS14P"
$PN"110"166;
"DQS14N"
$PN"111"167;
"DQS13P"
$PN"99"168;
"DQS13N"
$PN"100"26;
"DQS12P"
$PN"40"169;
"DQS12N"
$PN"41"170;
"DQS11P"
$PN"29"171;
"DQS11N"
$PN"30"172;
"DQS10P"
$PN"18"173;
"DQS10N"
$PN"19"174;
"DQS0P"
$PN"153"153;
"DQS0N"
$PN"152"154;
%"TAP"
"6","(-1700,3800)","2","mstr_standard","I62";
;
CDS_LIB"mstr_standard"
BODY_TYPE"PLUMBING"
HDL_TAP"TRUE";
"B \NAC \NWC"3;
"S \NAC"
BN"47"121;
%"TAP"
"6","(-1700,3850)","2","mstr_standard","I63";
;
CDS_LIB"mstr_standard"
BODY_TYPE"PLUMBING"
HDL_TAP"TRUE";
"B \NAC \NWC"3;
"S \NAC"
BN"46"112;
%"TAP"
"6","(-1700,3900)","2","mstr_standard","I64";
;
CDS_LIB"mstr_standard"
BODY_TYPE"PLUMBING"
HDL_TAP"TRUE";
"B \NAC \NWC"3;
"S \NAC"
BN"49"113;
%"TAP"
"6","(-1700,3750)","2","mstr_standard","I65";
;
CDS_LIB"mstr_standard"
BODY_TYPE"PLUMBING"
HDL_TAP"TRUE";
"B \NAC \NWC"3;
"S \NAC"
BN"44"120;
%"TAP"
"6","(-1700,3700)","2","mstr_standard","I66";
;
CDS_LIB"mstr_standard"
BODY_TYPE"PLUMBING"
HDL_TAP"TRUE";
"B \NAC \NWC"3;
"S \NAC"
BN"45"119;
%"TAP"
"6","(-1700,3650)","2","mstr_standard","I67";
;
CDS_LIB"mstr_standard"
BODY_TYPE"PLUMBING"
HDL_TAP"TRUE";
"B \NAC \NWC"3;
"S \NAC"
BN"42"118;
%"TAP"
"6","(-1700,3600)","2","mstr_standard","I68";
;
CDS_LIB"mstr_standard"
BODY_TYPE"PLUMBING"
HDL_TAP"TRUE";
"B \NAC \NWC"3;
"S \NAC"
BN"43"117;
%"TAP"
"6","(-1700,3550)","2","mstr_standard","I69";
;
CDS_LIB"mstr_standard"
BODY_TYPE"PLUMBING"
HDL_TAP"TRUE";
"B \NAC \NWC"3;
"S \NAC"
BN"40"111;
%"TAP"
"6","(900,5050)","2","mstr_standard","I7";
;
CDS_LIB"mstr_standard"
BODY_TYPE"PLUMBING"
HDL_TAP"TRUE";
"B \NAC \NWC"1;
"S \NAC"
BN"16"163;
%"TAP"
"6","(-1700,3450)","2","mstr_standard","I70";
;
CDS_LIB"mstr_standard"
BODY_TYPE"PLUMBING"
HDL_TAP"TRUE";
"B \NAC \NWC"3;
"S \NAC"
BN"38"109;
%"TAP"
"6","(-1700,3500)","2","mstr_standard","I71";
;
CDS_LIB"mstr_standard"
BODY_TYPE"PLUMBING"
HDL_TAP"TRUE";
"B \NAC \NWC"3;
"S \NAC"
BN"41"110;
%"TAP"
"6","(-1700,3300)","2","mstr_standard","I72";
;
CDS_LIB"mstr_standard"
BODY_TYPE"PLUMBING"
HDL_TAP"TRUE";
"B \NAC \NWC"3;
"S \NAC"
BN"37"103;
%"TAP"
"6","(-1700,3350)","2","mstr_standard","I73";
;
CDS_LIB"mstr_standard"
BODY_TYPE"PLUMBING"
HDL_TAP"TRUE";
"B \NAC \NWC"3;
"S \NAC"
BN"36"108;
%"TAP"
"6","(-1700,3400)","2","mstr_standard","I74";
;
CDS_LIB"mstr_standard"
BODY_TYPE"PLUMBING"
HDL_TAP"TRUE";
"B \NAC \NWC"3;
"S \NAC"
BN"39"102;
%"TAP"
"6","(-1700,3200)","2","mstr_standard","I75";
;
CDS_LIB"mstr_standard"
BODY_TYPE"PLUMBING"
HDL_TAP"TRUE";
"B \NAC \NWC"3;
"S \NAC"
BN"35"107;
%"TAP"
"6","(-1700,3250)","2","mstr_standard","I76";
;
CDS_LIB"mstr_standard"
BODY_TYPE"PLUMBING"
HDL_TAP"TRUE";
"B \NAC \NWC"3;
"S \NAC"
BN"34"104;
%"TAP"
"6","(-1700,3150)","2","mstr_standard","I77";
;
CDS_LIB"mstr_standard"
BODY_TYPE"PLUMBING"
HDL_TAP"TRUE";
"B \NAC \NWC"3;
"S \NAC"
BN"32"106;
%"TAP"
"6","(-1700,3100)","2","mstr_standard","I78";
;
CDS_LIB"mstr_standard"
BODY_TYPE"PLUMBING"
HDL_TAP"TRUE";
"B \NAC \NWC"3;
"S \NAC"
BN"33"105;
%"TAP"
"6","(-1700,3050)","2","mstr_standard","I79";
;
CDS_LIB"mstr_standard"
BODY_TYPE"PLUMBING"
HDL_TAP"TRUE";
"B \NAC \NWC"3;
"S \NAC"
BN"30"99;
%"TAP"
"6","(900,4850)","2","mstr_standard","I8";
;
CDS_LIB"mstr_standard"
BODY_TYPE"PLUMBING"
HDL_TAP"TRUE";
"B \NAC \NWC"1;
"S \NAC"
BN"14"167;
%"TAP"
"6","(-1700,2900)","2","mstr_standard","I80";
;
CDS_LIB"mstr_standard"
BODY_TYPE"PLUMBING"
HDL_TAP"TRUE";
"B \NAC \NWC"3;
"S \NAC"
BN"29"100;
%"TAP"
"6","(-1700,2950)","2","mstr_standard","I81";
;
CDS_LIB"mstr_standard"
BODY_TYPE"PLUMBING"
HDL_TAP"TRUE";
"B \NAC \NWC"3;
"S \NAC"
BN"28"101;
%"TAP"
"6","(-1700,3000)","2","mstr_standard","I82";
;
CDS_LIB"mstr_standard"
BODY_TYPE"PLUMBING"
HDL_TAP"TRUE";
"B \NAC \NWC"3;
"S \NAC"
BN"31"98;
%"TAP"
"6","(-1700,2850)","2","mstr_standard","I83";
;
CDS_LIB"mstr_standard"
BODY_TYPE"PLUMBING"
HDL_TAP"TRUE";
"B \NAC \NWC"3;
"S \NAC"
BN"26"93;
%"TAP"
"6","(-1700,2800)","2","mstr_standard","I84";
;
CDS_LIB"mstr_standard"
BODY_TYPE"PLUMBING"
HDL_TAP"TRUE";
"B \NAC \NWC"3;
"S \NAC"
BN"27"92;
%"TAP"
"6","(-1700,2650)","2","mstr_standard","I85";
;
CDS_LIB"mstr_standard"
BODY_TYPE"PLUMBING"
HDL_TAP"TRUE";
"B \NAC \NWC"3;
"S \NAC"
BN"22"95;
%"TAP"
"6","(-1700,2750)","2","mstr_standard","I86";
;
CDS_LIB"mstr_standard"
BODY_TYPE"PLUMBING"
HDL_TAP"TRUE";
"B \NAC \NWC"3;
"S \NAC"
BN"24"97;
%"TAP"
"6","(-1700,2700)","2","mstr_standard","I87";
;
CDS_LIB"mstr_standard"
BODY_TYPE"PLUMBING"
HDL_TAP"TRUE";
"B \NAC \NWC"3;
"S \NAC"
BN"25"96;
%"TAP"
"6","(-1700,2550)","2","mstr_standard","I88";
;
CDS_LIB"mstr_standard"
BODY_TYPE"PLUMBING"
HDL_TAP"TRUE";
"B \NAC \NWC"3;
"S \NAC"
BN"20"91;
%"TAP"
"6","(-1700,2600)","2","mstr_standard","I89";
;
CDS_LIB"mstr_standard"
BODY_TYPE"PLUMBING"
HDL_TAP"TRUE";
"B \NAC \NWC"3;
"S \NAC"
BN"23"94;
%"TAP"
"6","(700,5000)","2","mstr_standard","I9";
;
CDS_LIB"mstr_standard"
BODY_TYPE"PLUMBING"
HDL_TAP"TRUE";
"B \NAC \NWC"2;
"S \NAC"
BN"15"164;
%"TAP"
"6","(-1700,2500)","2","mstr_standard","I90";
;
CDS_LIB"mstr_standard"
BODY_TYPE"PLUMBING"
HDL_TAP"TRUE";
"B \NAC \NWC"3;
"S \NAC"
BN"21"90;
%"TAP"
"6","(-1700,2450)","2","mstr_standard","I91";
;
CDS_LIB"mstr_standard"
BODY_TYPE"PLUMBING"
HDL_TAP"TRUE";
"B \NAC \NWC"3;
"S \NAC"
BN"18"89;
%"TAP"
"6","(-1700,2400)","2","mstr_standard","I92";
;
CDS_LIB"mstr_standard"
BODY_TYPE"PLUMBING"
HDL_TAP"TRUE";
"B \NAC \NWC"3;
"S \NAC"
BN"19"88;
%"TAP"
"6","(-1700,2300)","2","mstr_standard","I93";
;
CDS_LIB"mstr_standard"
BODY_TYPE"PLUMBING"
HDL_TAP"TRUE";
"B \NAC \NWC"3;
"S \NAC"
BN"17"87;
%"TAP"
"6","(-1700,2350)","2","mstr_standard","I94";
;
CDS_LIB"mstr_standard"
BODY_TYPE"PLUMBING"
HDL_TAP"TRUE";
"B \NAC \NWC"3;
"S \NAC"
BN"16"81;
%"TAP"
"6","(-1700,2150)","2","mstr_standard","I95";
;
CDS_LIB"mstr_standard"
BODY_TYPE"PLUMBING"
HDL_TAP"TRUE";
"B \NAC \NWC"3;
"S \NAC"
BN"12"85;
%"TAP"
"6","(-1700,2200)","2","mstr_standard","I96";
;
CDS_LIB"mstr_standard"
BODY_TYPE"PLUMBING"
HDL_TAP"TRUE";
"B \NAC \NWC"3;
"S \NAC"
BN"15"86;
%"TAP"
"6","(-1700,2250)","2","mstr_standard","I97";
;
CDS_LIB"mstr_standard"
BODY_TYPE"PLUMBING"
HDL_TAP"TRUE";
"B \NAC \NWC"3;
"S \NAC"
BN"14"82;
%"TAP"
"6","(-1700,2050)","2","mstr_standard","I98";
;
CDS_LIB"mstr_standard"
BODY_TYPE"PLUMBING"
HDL_TAP"TRUE";
"B \NAC \NWC"3;
"S \NAC"
BN"10"83;
%"TAP"
"6","(-1700,2100)","2","mstr_standard","I99";
;
CDS_LIB"mstr_standard"
BODY_TYPE"PLUMBING"
HDL_TAP"TRUE";
"B \NAC \NWC"3;
"S \NAC"
BN"13"84;
END.
